(kicad_pcb
	(version 20260206)
	(generator "pcbnew")
	(generator_version "10.0")
	(general
		(thickness 1.6)
		(legacy_teardrops no)
	)
	(paper "A4")
	(title_block
		(title "v1-tray-backplane — T6M_tray_BP_c_1023_1120.brd")
		(comment 1 "Open CloudServer (Microsoft) / footprints 85-89 of 170")
	)
	(layers
		(0 "F.Cu" signal "TOP")
		(4 "In1.Cu" signal "GND")
		(6 "In2.Cu" signal "IN1")
		(8 "In3.Cu" signal "VCC")
		(10 "In4.Cu" signal "VCC1")
		(12 "In5.Cu" signal "IN2")
		(14 "In6.Cu" signal "GND1")
		(2 "B.Cu" signal "BOTTOM")
		(9 "F.Adhes" user "F.Adhesive")
		(11 "B.Adhes" user "B.Adhesive")
		(13 "F.Paste" user "Package Geometry/Pastemask Top")
		(15 "B.Paste" user "Package Geometry/Pastemask Bottom")
		(5 "F.SilkS" user "Ref Des/Silkscreen Top")
		(7 "B.SilkS" user "Ref Des/Silkscreen Bottom")
		(1 "F.Mask" user "Board Geometry/Soldermask Top")
		(3 "B.Mask" user "Board Geometry/Soldermask Bottom")
		(17 "Dwgs.User" user "User.Drawings")
		(19 "Cmts.User" user "User.Comments")
		(21 "Eco1.User" user "User.Eco1")
		(23 "Eco2.User" user "User.Eco2")
		(25 "Edge.Cuts" user "Board Geometry/Outline")
		(27 "Margin" user)
		(31 "F.CrtYd" user "Package Geometry/Place Bound Top")
		(29 "B.CrtYd" user "Package Geometry/Place Bound Bottom")
		(35 "F.Fab" user "Ref Des/Assembly Top")
		(33 "B.Fab" user "Ref Des/Assembly Bottom")
	)
	(footprint ""
		(layer "F.Cu")
		(at 159.047942 -34.3154 90)
		(property "Reference" "L1"
			(at -22.733 32.882078 90)
			(unlocked yes)
			(layer "F.SilkS")
			(effects
				(font
					(size 0.7874 0.5842)
					(thickness 0.1524)
				)
				(justify left)
			)
		)
		(property "Value" ""
			(at 0 0 90)
			(layer "F.Fab")
			(effects
				(font
					(size 1.27 1.27)
				)
			)
		)
		(duplicate_pad_numbers_are_jumpers no)
		(fp_line
			(start -1.905 -0.8636)
			(end 1.905 -0.8636)
			(stroke
				(width 0.1524)
				(type default)
			)
			(layer "F.SilkS")
		)
		(fp_line
			(start 1.905 0.8382)
			(end 1.905 -0.8382)
			(stroke
				(width 0.1524)
				(type default)
			)
			(layer "F.SilkS")
		)
		(fp_line
			(start 0.127 0.8382)
			(end 0.127 -0.8382)
			(stroke
				(width 0.1524)
				(type default)
			)
			(layer "F.SilkS")
		)
		(fp_line
			(start -0.127 0.8382)
			(end -0.127 -0.8382)
			(stroke
				(width 0.1524)
				(type default)
			)
			(layer "F.SilkS")
		)
		(fp_line
			(start -1.905 0.8382)
			(end -1.905 -0.8382)
			(stroke
				(width 0.1524)
				(type default)
			)
			(layer "F.SilkS")
		)
		(fp_line
			(start 1.905 0.8636)
			(end -1.905 0.8636)
			(stroke
				(width 0.1524)
				(type default)
			)
			(layer "F.SilkS")
		)
		(fp_rect
			(start -1.524 0.7112)
			(end 1.524 -0.7366)
			(stroke
				(width 0)
				(type default)
			)
			(fill no)
			(layer "F.CrtYd")
		)
		(pad "1" smd rect
			(at 0.94996 0 90)
			(size 1.1176 1.3716)
			(layers "F.Cu" "F.Mask" "F.Paste")
			(net "P3V3_10G_1_VCCT_L")
		)
		(pad "2" smd rect
			(at -0.94996 0 90)
			(size 1.1176 1.3716)
			(layers "F.Cu" "F.Mask" "F.Paste")
			(net "P3V3_10G_1_VCCT")
		)
	)
	(footprint ""
		(layer "F.Cu")
		(at 172.48505 -28.4099 180)
		(property "Reference" "U3"
			(at -6.976364 -9.255252 0)
			(unlocked yes)
			(layer "F.SilkS")
			(effects
				(font
					(size 0.7874 0.5842)
					(thickness 0.1524)
				)
				(justify left)
			)
		)
		(property "Value" ""
			(at 0 0 180)
			(layer "F.Fab")
			(effects
				(font
					(size 1.27 1.27)
				)
			)
		)
		(duplicate_pad_numbers_are_jumpers no)
		(fp_line
			(start 6.949948 8.32993)
			(end 6.949948 5.7912)
			(stroke
				(width 0.1524)
				(type default)
			)
			(layer "F.SilkS")
		)
		(fp_line
			(start 6.949948 4.572)
			(end 6.949948 0)
			(stroke
				(width 0.1524)
				(type default)
			)
			(layer "F.SilkS")
		)
		(fp_line
			(start 6.949948 0)
			(end 6.949948 -3.670046)
			(stroke
				(width 0.1524)
				(type default)
			)
			(layer "F.SilkS")
		)
		(fp_line
			(start 6.949948 -3.670046)
			(end 0 -3.670046)
			(stroke
				(width 0.1524)
				(type default)
			)
			(layer "F.SilkS")
		)
		(fp_line
			(start 0 -3.670046)
			(end -6.949948 -3.670046)
			(stroke
				(width 0.1524)
				(type default)
			)
			(layer "F.SilkS")
		)
		(fp_line
			(start -6.949948 8.32993)
			(end 6.949948 8.32993)
			(stroke
				(width 0.1524)
				(type default)
			)
			(layer "F.SilkS")
		)
		(fp_line
			(start -6.949948 5.7912)
			(end -6.949948 8.32993)
			(stroke
				(width 0.1524)
				(type default)
			)
			(layer "F.SilkS")
		)
		(fp_line
			(start -6.949948 0)
			(end -6.949948 4.5466)
			(stroke
				(width 0.1524)
				(type default)
			)
			(layer "F.SilkS")
		)
		(fp_line
			(start -6.949948 -3.670046)
			(end -6.949948 0)
			(stroke
				(width 0.1524)
				(type default)
			)
			(layer "F.SilkS")
		)
		(fp_poly
			(pts
				(xy -13.335 1.3208) (xy -15.113 2.3368) (xy -15.113 0.3048)
			)
			(stroke
				(width 0)
				(type default)
			)
			(fill yes)
			(layer "F.SilkS")
		)
		(fp_poly
			(pts
				(arc
					(start 4.933188 5.180076)
					(mid 7.066788 5.180076)
					(end 4.933188 5.180076)
				)
			)
			(stroke
				(width 0)
				(type default)
			)
			(fill no)
			(layer "B.CrtYd")
		)
		(fp_poly
			(pts
				(arc
					(start -7.06755 5.180076)
					(mid -4.932426 5.180076)
					(end -7.06755 5.180076)
				)
			)
			(stroke
				(width 0)
				(type default)
			)
			(fill no)
			(layer "B.CrtYd")
		)
		(fp_poly
			(pts
				(xy -6.949948 8.32993) (xy 6.949948 8.32993) (xy 6.949948 -3.670046) (xy -6.949948 -3.670046)
			)
			(stroke
				(width 0)
				(type default)
			)
			(fill no)
			(layer "F.CrtYd")
		)
		(fp_line
			(start 6.949948 8.32993)
			(end 6.949948 -3.670046)
			(stroke
				(width 0.1)
				(type default)
			)
			(layer "F.Fab")
		)
		(fp_line
			(start 6.949948 -3.670046)
			(end -6.949948 -3.670046)
			(stroke
				(width 0.1)
				(type default)
			)
			(layer "F.Fab")
		)
		(fp_line
			(start -6.700012 0)
			(end -6.949948 0)
			(stroke
				(width 0.1)
				(type default)
			)
			(layer "F.Fab")
		)
		(fp_line
			(start -6.949948 8.32993)
			(end 6.949948 8.32993)
			(stroke
				(width 0.1)
				(type default)
			)
			(layer "F.Fab")
		)
		(fp_line
			(start -6.949948 0)
			(end -6.949948 8.32993)
			(stroke
				(width 0.1)
				(type default)
			)
			(layer "F.Fab")
		)
		(fp_line
			(start -6.949948 -3.670046)
			(end -6.949948 0)
			(stroke
				(width 0.1)
				(type default)
			)
			(layer "F.Fab")
		)
		(fp_poly
			(pts
				(xy -6.9596 0) (xy -8.7376 1.016) (xy -8.7376 -1.016)
			)
			(stroke
				(width 0)
				(type default)
			)
			(fill yes)
			(layer "F.Fab")
		)
		(fp_text user "A13"
			(at 12.341098 0.57658 90)
			(unlocked yes)
			(layer "F.SilkS")
			(effects
				(font
					(size 0.7874 0.5842)
					(thickness 0.1524)
				)
				(justify left)
			)
		)
		(fp_text user "B13"
			(at 12.310872 -4.63042 90)
			(unlocked yes)
			(layer "F.SilkS")
			(effects
				(font
					(size 0.7874 0.5842)
					(thickness 0.1524)
				)
				(justify left)
			)
		)
		(fp_text user "A1"
			(at -9.41578 -9.128252 0)
			(unlocked yes)
			(layer "F.SilkS")
			(effects
				(font
					(size 0.7874 0.5842)
					(thickness 0.1524)
				)
				(justify left)
			)
		)
		(fp_text user "B1"
			(at -9.46658 -10.149078 0)
			(unlocked yes)
			(layer "F.SilkS")
			(effects
				(font
					(size 0.7874 0.5842)
					(thickness 0.1524)
				)
				(justify left)
			)
		)
		(fp_text user "A13"
			(at 7.360666 -0.091948 180)
			(unlocked yes)
			(layer "F.Fab")
			(effects
				(font
					(size 0.7874 0.5842)
					(thickness 0.000001)
				)
				(justify left)
			)
		)
		(fp_text user "B13"
			(at 7.360666 -2.601722 180)
			(unlocked yes)
			(layer "F.Fab")
			(effects
				(font
					(size 0.7874 0.5842)
					(thickness 0.000001)
				)
				(justify left)
			)
		)
		(fp_text user "A1"
			(at -8.609584 1.330452 180)
			(unlocked yes)
			(layer "F.Fab")
			(effects
				(font
					(size 0.7874 0.5842)
					(thickness 0.000001)
				)
				(justify left)
			)
		)
		(fp_text user "B1"
			(at -8.685784 -2.601722 180)
			(unlocked yes)
			(layer "F.Fab")
			(effects
				(font
					(size 0.7874 0.5842)
					(thickness 0.000001)
				)
				(justify left)
			)
		)
		(pad "" np_thru_hole circle
			(at -5.999988 5.180076 180)
			(size 1.6002 1.6002)
			(drill 1.6002)
			(layers "*.Cu" "*.Mask")
			(clearance 0.381)
			(thermal_gap 0.381)
		)
		(pad "" np_thru_hole circle
			(at 5.999988 5.180076 180)
			(size 1.6002 1.6002)
			(drill 1.6002)
			(layers "*.Cu" "*.Mask")
			(clearance 0.381)
			(thermal_gap 0.381)
		)
		(pad "A1" smd rect
			(at -4.59994 0 180)
			(size 0.381 1.8542)
			(layers "F.Cu" "F.Mask" "F.Paste")
			(net "GND")
		)
		(pad "A2" smd rect
			(at -3.800094 0 180)
			(size 0.381 1.8542)
			(layers "F.Cu" "F.Mask" "F.Paste")
			(net "SAS_BLAD1_RX5_P")
		)
		(pad "A3" smd rect
			(at -2.999994 0 180)
			(size 0.381 1.8542)
			(layers "F.Cu" "F.Mask" "F.Paste")
			(net "SAS_BLAD1_RX5_N")
		)
		(pad "A4" smd rect
			(at -2.199894 0 180)
			(size 0.381 1.8542)
			(layers "F.Cu" "F.Mask" "F.Paste")
			(net "GND")
		)
		(pad "A5" smd rect
			(at -1.400048 0 180)
			(size 0.381 1.8542)
			(layers "F.Cu" "F.Mask" "F.Paste")
			(net "SAS_BLAD1_RX6_P")
		)
		(pad "A6" smd rect
			(at -0.599948 0 180)
			(size 0.381 1.8542)
			(layers "F.Cu" "F.Mask" "F.Paste")
			(net "SAS_BLAD1_RX6_N")
		)
		(pad "A7" smd rect
			(at 0.199898 0 180)
			(size 0.381 1.8542)
			(layers "F.Cu" "F.Mask" "F.Paste")
			(net "GND")
		)
		(pad "A8" smd rect
			(at 0.999998 0 180)
			(size 0.381 1.8542)
			(layers "F.Cu" "F.Mask" "F.Paste")
			(net "SAS_BLAD1_RX7_P")
		)
		(pad "A9" smd rect
			(at 1.800098 0 180)
			(size 0.381 1.8542)
			(layers "F.Cu" "F.Mask" "F.Paste")
			(net "SAS_BLAD1_RX7_N")
		)
		(pad "A10" smd rect
			(at 2.599944 0 180)
			(size 0.381 1.8542)
			(layers "F.Cu" "F.Mask" "F.Paste")
			(net "GND")
		)
		(pad "A11" smd rect
			(at 3.400044 0 180)
			(size 0.381 1.8542)
			(layers "F.Cu" "F.Mask" "F.Paste")
			(net "SAS_BLAD1_RX8_P")
		)
		(pad "A12" smd rect
			(at 4.19989 0 180)
			(size 0.381 1.8542)
			(layers "F.Cu" "F.Mask" "F.Paste")
			(net "SAS_BLAD1_RX8_N")
		)
		(pad "A13" smd rect
			(at 4.99999 0 180)
			(size 0.381 1.8542)
			(layers "F.Cu" "F.Mask" "F.Paste")
			(net "GND")
		)
		(pad "B1" smd rect
			(at -4.99999 -2.510028 180)
			(size 0.381 1.8542)
			(layers "F.Cu" "F.Mask" "F.Paste")
			(net "GND")
		)
		(pad "B2" smd rect
			(at -4.19989 -2.510028 180)
			(size 0.381 1.8542)
			(layers "F.Cu" "F.Mask" "F.Paste")
			(net "SAS_BLAD1_TX5_P")
		)
		(pad "B3" smd rect
			(at -3.400044 -2.510028 180)
			(size 0.381 1.8542)
			(layers "F.Cu" "F.Mask" "F.Paste")
			(net "SAS_BLAD1_TX5_N")
		)
		(pad "B4" smd rect
			(at -2.599944 -2.510028 180)
			(size 0.381 1.8542)
			(layers "F.Cu" "F.Mask" "F.Paste")
			(net "GND")
		)
		(pad "B5" smd rect
			(at -1.800098 -2.510028 180)
			(size 0.381 1.8542)
			(layers "F.Cu" "F.Mask" "F.Paste")
			(net "SAS_BLAD1_TX6_P")
		)
		(pad "B6" smd rect
			(at -0.999998 -2.510028 180)
			(size 0.381 1.8542)
			(layers "F.Cu" "F.Mask" "F.Paste")
			(net "SAS_BLAD1_TX6_N")
		)
		(pad "B7" smd rect
			(at -0.199898 -2.510028 180)
			(size 0.381 1.8542)
			(layers "F.Cu" "F.Mask" "F.Paste")
			(net "GND")
		)
		(pad "B8" smd rect
			(at 0.599948 -2.510028 180)
			(size 0.381 1.8542)
			(layers "F.Cu" "F.Mask" "F.Paste")
			(net "SAS_BLAD1_TX7_P")
		)
		(pad "B9" smd rect
			(at 1.400048 -2.510028 180)
			(size 0.381 1.8542)
			(layers "F.Cu" "F.Mask" "F.Paste")
			(net "SAS_BLAD1_TX7_N")
		)
		(pad "B10" smd rect
			(at 2.199894 -2.510028 180)
			(size 0.381 1.8542)
			(layers "F.Cu" "F.Mask" "F.Paste")
			(net "GND")
		)
		(pad "B11" smd rect
			(at 2.999994 -2.510028 180)
			(size 0.381 1.8542)
			(layers "F.Cu" "F.Mask" "F.Paste")
			(net "SAS_BLAD1_TX8_P")
		)
		(pad "B12" smd rect
			(at 3.800094 -2.510028 180)
			(size 0.381 1.8542)
			(layers "F.Cu" "F.Mask" "F.Paste")
			(net "SAS_BLAD1_TX8_N")
		)
		(pad "B13" smd rect
			(at 4.59994 -2.510028 180)
			(size 0.381 1.8542)
			(layers "F.Cu" "F.Mask" "F.Paste")
			(net "GND")
		)
		(zone
			(layer "F.Cu")
			(hatch none 0.5)
			(connect_pads
				(clearance 0)
			)
			(min_thickness 0.25)
			(keepout
				(tracks not_allowed)
				(vias allowed)
				(pads allowed)
				(copperpour not_allowed)
				(footprints allowed)
			)
			(placement
				(enabled no)
				(sheetname "")
			)
			(fill
				(thermal_gap 0.5)
				(thermal_bridge_width 0.5)
				(island_removal_mode 0)
			)
			(polygon
				(pts
					(xy 167.40505 -36.73983) (xy 165.565074 -36.73983) (xy 165.565074 -35.279838) (xy 167.40505 -35.279838)
				)
			)
		)
		(zone
			(layer "F.Cu")
			(hatch none 0.5)
			(connect_pads
				(clearance 0)
			)
			(min_thickness 0.25)
			(keepout
				(tracks not_allowed)
				(vias allowed)
				(pads allowed)
				(copperpour not_allowed)
				(footprints allowed)
			)
			(placement
				(enabled no)
				(sheetname "")
			)
			(fill
				(thermal_gap 0.5)
				(thermal_bridge_width 0.5)
				(island_removal_mode 0)
			)
			(polygon
				(pts
					(xy 179.405026 -36.73983) (xy 177.56505 -36.73983) (xy 177.56505 -35.279838) (xy 179.405026 -35.279838)
				)
			)
		)
		(zone
			(layers "F.Cu" "B.Cu" "In1.Cu" "In2.Cu" "In3.Cu" "In4.Cu" "In5.Cu" "In6.Cu")
			(hatch none 0.5)
			(connect_pads
				(clearance 0)
			)
			(min_thickness 0.25)
			(keepout
				(tracks not_allowed)
				(vias allowed)
				(pads allowed)
				(copperpour not_allowed)
				(footprints allowed)
			)
			(placement
				(enabled no)
				(sheetname "")
			)
			(fill
				(thermal_gap 0.5)
				(thermal_bridge_width 0.5)
				(island_removal_mode 0)
			)
			(polygon
				(pts
					(arc
						(start 167.704008 -33.589976)
						(mid 165.266116 -33.589976)
						(end 167.704008 -33.589976)
					)
				)
			)
		)
		(zone
			(layers "F.Cu" "B.Cu" "In1.Cu" "In2.Cu" "In3.Cu" "In4.Cu" "In5.Cu" "In6.Cu")
			(hatch none 0.5)
			(connect_pads
				(clearance 0)
			)
			(min_thickness 0.25)
			(keepout
				(tracks not_allowed)
				(vias allowed)
				(pads allowed)
				(copperpour not_allowed)
				(footprints allowed)
			)
			(placement
				(enabled no)
				(sheetname "")
			)
			(fill
				(thermal_gap 0.5)
				(thermal_bridge_width 0.5)
				(island_removal_mode 0)
			)
			(polygon
				(pts
					(arc
						(start 179.704746 -33.589976)
						(mid 177.26533 -33.589976)
						(end 179.704746 -33.589976)
					)
				)
			)
		)
	)
	(footprint ""
		(layer "F.Cu")
		(at 378.431552 -23.636478)
		(property "Reference" "R50"
			(at 33.528 16.545052 0)
			(unlocked yes)
			(layer "F.SilkS")
			(effects
				(font
					(size 0.7874 0.5842)
					(thickness 0.1524)
				)
				(justify left)
			)
		)
		(property "Value" ""
			(at 0 0 0)
			(layer "F.Fab")
			(effects
				(font
					(size 1.27 1.27)
				)
			)
		)
		(duplicate_pad_numbers_are_jumpers no)
		(fp_line
			(start -0.7874 -0.4064)
			(end 0.7874 -0.4064)
			(stroke
				(width 0.1524)
				(type default)
			)
			(layer "F.SilkS")
		)
		(fp_line
			(start -0.7874 0.4064)
			(end -0.7874 -0.4064)
			(stroke
				(width 0.1524)
				(type default)
			)
			(layer "F.SilkS")
		)
		(fp_line
			(start 0.7874 -0.4064)
			(end 0.7874 0.4064)
			(stroke
				(width 0.1524)
				(type default)
			)
			(layer "F.SilkS")
		)
		(fp_line
			(start 0.7874 0.4064)
			(end -0.7874 0.4064)
			(stroke
				(width 0.1524)
				(type default)
			)
			(layer "F.SilkS")
		)
		(fp_poly
			(pts
				(xy -0.508 0.2794) (xy -0.508 0.2286) (xy -0.635 0.2286) (xy -0.635 -0.254) (xy -0.5334 -0.254)
				(xy -0.5334 -0.2794) (xy 0.5334 -0.2794) (xy 0.5334 -0.254) (xy 0.635 -0.254) (xy 0.635 0.254) (xy 0.5334 0.254)
				(xy 0.5334 0.2794)
			)
			(stroke
				(width 0)
				(type default)
			)
			(fill no)
			(layer "F.CrtYd")
		)
		(pad "1" smd rect
			(at 0.40005 0)
			(size 0.4572 0.508)
			(layers "F.Cu" "F.Mask" "F.Paste")
			(net "GND")
		)
		(pad "2" smd rect
			(at -0.40005 0)
			(size 0.4572 0.508)
			(layers "F.Cu" "F.Mask" "F.Paste")
			(net "ENET10G_3_TX_FAULT")
		)
	)
	(footprint ""
		(layer "F.Cu")
		(at 364.0836 -3.0988 90)
		(property "Reference" "C29"
			(at -2.286 -2.022348 90)
			(unlocked yes)
			(layer "F.SilkS")
			(effects
				(font
					(size 0.7874 0.5842)
					(thickness 0.1524)
				)
				(justify left)
			)
		)
		(property "Value" ""
			(at 0 0 90)
			(layer "F.Fab")
			(effects
				(font
					(size 1.27 1.27)
				)
			)
		)
		(duplicate_pad_numbers_are_jumpers no)
		(fp_line
			(start 0.7874 -0.4064)
			(end 0.7874 0.4064)
			(stroke
				(width 0.1524)
				(type default)
			)
			(layer "F.SilkS")
		)
		(fp_line
			(start -0.7874 -0.4064)
			(end 0.7874 -0.4064)
			(stroke
				(width 0.1524)
				(type default)
			)
			(layer "F.SilkS")
		)
		(fp_line
			(start 0 0.381)
			(end 0 -0.381)
			(stroke
				(width 0.1524)
				(type default)
			)
			(layer "F.SilkS")
		)
		(fp_line
			(start 0.7874 0.4064)
			(end -0.7874 0.4064)
			(stroke
				(width 0.1524)
				(type default)
			)
			(layer "F.SilkS")
		)
		(fp_line
			(start -0.7874 0.4064)
			(end -0.7874 -0.4064)
			(stroke
				(width 0.1524)
				(type default)
			)
			(layer "F.SilkS")
		)
		(fp_poly
			(pts
				(xy -0.5334 0.254) (xy -0.635 0.254) (xy -0.635 0.2286) (xy -0.635 -0.254) (xy -0.5334 -0.254) (xy -0.5334 -0.2794)
				(xy 0.5334 -0.2794) (xy 0.5334 -0.254) (xy 0.635 -0.254) (xy 0.635 0.254) (xy 0.5334 0.254) (xy 0.5334 0.2794)
				(xy -0.508 0.2794) (xy -0.5334 0.2794)
			)
			(stroke
				(width 0)
				(type default)
			)
			(fill no)
			(layer "F.CrtYd")
		)
		(pad "1" smd rect
			(at 0.40005 0 90)
			(size 0.4572 0.508)
			(layers "F.Cu" "F.Mask" "F.Paste")
			(net "P3V3_10G_3_VCCR")
		)
		(pad "2" smd rect
			(at -0.40005 0 90)
			(size 0.4572 0.508)
			(layers "F.Cu" "F.Mask" "F.Paste")
			(net "GND")
		)
	)
	(footprint ""
		(layer "F.Cu")
		(at 154.89936 -25.439878 180)
		(property "Reference" "R11"
			(at -33.71088 -17.844008 0)
			(unlocked yes)
			(layer "F.SilkS")
			(effects
				(font
					(size 0.7874 0.5842)
					(thickness 0.1524)
				)
				(justify left)
			)
		)
		(property "Value" ""
			(at 0 0 180)
			(layer "F.Fab")
			(effects
				(font
					(size 1.27 1.27)
				)
			)
		)
		(duplicate_pad_numbers_are_jumpers no)
		(fp_line
			(start 0.7874 0.4064)
			(end -0.7874 0.4064)
			(stroke
				(width 0.1524)
				(type default)
			)
			(layer "F.SilkS")
		)
		(fp_line
			(start 0.7874 -0.4064)
			(end 0.7874 0.4064)
			(stroke
				(width 0.1524)
				(type default)
			)
			(layer "F.SilkS")
		)
		(fp_line
			(start -0.7874 0.4064)
			(end -0.7874 -0.4064)
			(stroke
				(width 0.1524)
				(type default)
			)
			(layer "F.SilkS")
		)
		(fp_line
			(start -0.7874 -0.4064)
			(end 0.7874 -0.4064)
			(stroke
				(width 0.1524)
				(type default)
			)
			(layer "F.SilkS")
		)
		(fp_poly
			(pts
				(xy -0.508 0.2794) (xy -0.508 0.2286) (xy -0.635 0.2286) (xy -0.635 -0.254) (xy -0.5334 -0.254)
				(xy -0.5334 -0.2794) (xy 0.5334 -0.2794) (xy 0.5334 -0.254) (xy 0.635 -0.254) (xy 0.635 0.254) (xy 0.5334 0.254)
				(xy 0.5334 0.2794)
			)
			(stroke
				(width 0)
				(type default)
			)
			(fill no)
			(layer "F.CrtYd")
		)
		(pad "1" smd rect
			(at 0.40005 0 180)
			(size 0.4572 0.508)
			(layers "F.Cu" "F.Mask" "F.Paste")
			(net "P3V3_BLAD1")
		)
		(pad "2" smd rect
			(at -0.40005 0 180)
			(size 0.4572 0.508)
			(layers "F.Cu" "F.Mask" "F.Paste")
			(net "ENET10G_1_RS0")
		)
	)
)
